#ISCELL
  mstr_misc dns *
  *
#ISCELL
  mstr_symbols cad_note *
  *
#ISCELL
  mstr_symbols intel_corp_bpage *
  *
#CELL
  dev_discrete cap_a *
  page251_i1
#CELL
  mstr_discrete diode *
  page251_i10
#CELL
  mstr_discrete res *
  page251_i11
#CELL
  mstr_discrete diode *
  page251_i12
#CELL
  mstr_discrete res *
  page251_i13
#CELL
  mstr_discrete res *
  page251_i14
#CELL
  mstr_discrete res *
  page251_i15
#CELL
  dev_discrete cap_a *
  page251_i16
#ISCELL
  mstr_symbols gnd *
  page251_i17
#ISCELL
  mstr_standard offpage *
  page251_i18
#CELL
  mstr_ttl ttl1g07_a *
  page251_i19
#ISCELL
  mstr_symbols p3v3_stby *
  page251_i20
#CELL
  dev_discrete cap_a *
  page251_i21
#ISCELL
  mstr_symbols gnd *
  page251_i22
#ISCELL
  mstr_standard offpage *
  page251_i23
#CELL
  mstr_conn conn6_c74770005 *
  page251_i25
#CELL
  mstr_discrete diode *
  page251_i26
#CELL
  mstr_discrete res *
  page251_i27
#ISCELL
  mstr_standard offpage *
  page251_i28
#CELL
  dev_discrete cap_a *
  page251_i29
#CELL
  mstr_discrete cap *
  page251_i3
#ISCELL
  mstr_symbols gnd *
  page251_i30
#CELL
  mstr_discrete res *
  page251_i31
#ISCELL
  mstr_symbols p3v3_stby *
  page251_i32
#ISCELL
  mstr_symbols gnd *
  page251_i4
#CELL
  mstr_discrete res *
  page251_i5
#ISCELL
  mstr_symbols p12v_fan *
  page251_i6
#ISCELL
  mstr_symbols p3v3_stby *
  page251_i7
#ISCELL
  mstr_symbols gnd *
  page251_i8
#ISCELL
  mstr_symbols p5v_stby *
  page251_i9
